# SCM (Grand Teton) — schematic netlist excerpt (pin names and nets, part order shuffled) for the footprints in the layout excerpt that follows; sources: Cadence DE-HDL packaged netlist, KiCad conversion of 12092022_DA0F0TMDCD0_F0T_Management_Board_D_brd_V3_OCP.brd

R600  Q_RES  750 1% CHIP  pkg 0402LF  page 47 : A = LED_POSTCODE_4 ; B = LED_POSTCODE_4_R
R869  Q_RES  0 5% EMPTY  pkg 0402LF  page 52 : A = PWRGD_P1V8_AUX_R3 ; B = EN_P3V3_RGM_R

(kicad_pcb
	(version 20260206)
	(generator "pcbnew")
	(generator_version "10.0")
	(general
		(thickness 1.6)
		(legacy_teardrops no)
	)
	(paper "A4")
	(title_block
		(title "12092022_DA0F0TMDCD0_F0T_Management_Board_D_brd_V3_OCP.brd")
		(comment 1 "Grand Teton / footprints 122-123 of 1440")
	)
	(layers
		(0 "F.Cu" signal "TOP")
		(4 "In1.Cu" signal "GND")
		(6 "In2.Cu" signal "IN1")
		(8 "In3.Cu" signal "GND1")
		(10 "In4.Cu" signal "IN2")
		(12 "In5.Cu" signal "VCC")
		(14 "In6.Cu" signal "VCC1")
		(16 "In7.Cu" signal "IN3")
		(18 "In8.Cu" signal "GND2")
		(20 "In9.Cu" signal "IN4")
		(22 "In10.Cu" signal "GND3")
		(2 "B.Cu" signal "BOTTOM")
		(9 "F.Adhes" user "F.Adhesive")
		(11 "B.Adhes" user "B.Adhesive")
		(13 "F.Paste" user "Package Geometry/Pastemask Top")
		(15 "B.Paste" user "Package Geometry/Pastemask Bottom")
		(5 "F.SilkS" user "Ref Des/Silkscreen Top")
		(7 "B.SilkS" user "Ref Des/Silkscreen Bottom")
		(1 "F.Mask" user "Board Geometry/Soldermask Top")
		(3 "B.Mask" user "Board Geometry/Soldermask Bottom")
		(17 "Dwgs.User" user "User.Drawings")
		(19 "Cmts.User" user "User.Comments")
		(21 "Eco1.User" user "User.Eco1")
		(23 "Eco2.User" user "User.Eco2")
		(25 "Edge.Cuts" user "Board Geometry/Outline")
		(27 "Margin" user)
		(31 "F.CrtYd" user "Package Geometry/Place Bound Top")
		(29 "B.CrtYd" user "Package Geometry/Place Bound Bottom")
		(35 "F.Fab" user "Ref Des/Assembly Top")
		(33 "B.Fab" user "Ref Des/Assembly Bottom")
	)
	(footprint ""
		(layer "F.Cu")
		(at 78.6892 -34.1122)
		(property "Reference" "R600"
			(at 0 0 0)
			(layer "F.SilkS")
			(hide yes)
			(effects
				(font
					(size 1.27 1.27)
				)
			)
		)
		(property "Value" ""
			(at 0 0 0)
			(layer "F.Fab")
			(effects
				(font
					(size 1.27 1.27)
				)
			)
		)
		(duplicate_pad_numbers_are_jumpers no)
		(fp_line
			(start -0.7874 -0.4064)
			(end 0.7874 -0.4064)
			(stroke
				(width 0.1524)
				(type default)
			)
			(layer "F.SilkS")
		)
		(fp_line
			(start -0.7874 0.4064)
			(end -0.7874 -0.4064)
			(stroke
				(width 0.1524)
				(type default)
			)
			(layer "F.SilkS")
		)
		(fp_line
			(start 0.7874 -0.4064)
			(end 0.7874 0.4064)
			(stroke
				(width 0.1524)
				(type default)
			)
			(layer "F.SilkS")
		)
		(fp_line
			(start 0.7874 0.4064)
			(end -0.7874 0.4064)
			(stroke
				(width 0.1524)
				(type default)
			)
			(layer "F.SilkS")
		)
		(fp_line
			(start -0.67945 -0.305054)
			(end -0.12065 -0.305054)
			(stroke
				(width 0.1)
				(type default)
			)
			(layer "F.Fab")
		)
		(fp_line
			(start -0.67945 0.3048)
			(end -0.67945 -0.305054)
			(stroke
				(width 0.1)
				(type default)
			)
			(layer "F.Fab")
		)
		(fp_line
			(start -0.12065 -0.305054)
			(end -0.12065 -0.2794)
			(stroke
				(width 0.1)
				(type default)
			)
			(layer "F.Fab")
		)
		(fp_line
			(start -0.12065 -0.2794)
			(end 0.12065 -0.2794)
			(stroke
				(width 0.1)
				(type default)
			)
			(layer "F.Fab")
		)
		(fp_line
			(start -0.12065 0.2794)
			(end -0.12065 0.3048)
			(stroke
				(width 0.1)
				(type default)
			)
			(layer "F.Fab")
		)
		(fp_line
			(start -0.12065 0.3048)
			(end -0.67945 0.3048)
			(stroke
				(width 0.1)
				(type default)
			)
			(layer "F.Fab")
		)
		(fp_line
			(start 0.120396 0.2794)
			(end -0.12065 0.2794)
			(stroke
				(width 0.1)
				(type default)
			)
			(layer "F.Fab")
		)
		(fp_line
			(start 0.120396 0.3048)
			(end 0.120396 0.2794)
			(stroke
				(width 0.1)
				(type default)
			)
			(layer "F.Fab")
		)
		(fp_line
			(start 0.12065 -0.3048)
			(end 0.67945 -0.3048)
			(stroke
				(width 0.1)
				(type default)
			)
			(layer "F.Fab")
		)
		(fp_line
			(start 0.12065 -0.2794)
			(end 0.12065 -0.3048)
			(stroke
				(width 0.1)
				(type default)
			)
			(layer "F.Fab")
		)
		(fp_line
			(start 0.67945 -0.3048)
			(end 0.67945 0.3048)
			(stroke
				(width 0.1)
				(type default)
			)
			(layer "F.Fab")
		)
		(fp_line
			(start 0.67945 0.3048)
			(end 0.120396 0.3048)
			(stroke
				(width 0.1)
				(type default)
			)
			(layer "F.Fab")
		)
		(pad "1" smd circle
			(at -0.40005 0)
			(size 0 0)
			(layers "F.Cu" "F.Mask" "F.Paste")
			(net "LED_POSTCODE_4")
		)
		(pad "2" smd circle
			(at 0.40005 0)
			(size 0 0)
			(layers "F.Cu" "F.Mask" "F.Paste")
			(net "LED_POSTCODE_4_R")
		)
	)
	(footprint ""
		(layer "F.Cu")
		(at 70.4342 -27.2796 90)
		(property "Reference" "R869"
			(at 0 0 90)
			(layer "F.SilkS")
			(hide yes)
			(effects
				(font
					(size 1.27 1.27)
				)
			)
		)
		(property "Value" ""
			(at 0 0 90)
			(layer "F.Fab")
			(effects
				(font
					(size 1.27 1.27)
				)
			)
		)
		(duplicate_pad_numbers_are_jumpers no)
		(fp_line
			(start 0.7874 -0.4064)
			(end 0.7874 0.4064)
			(stroke
				(width 0.1524)
				(type default)
			)
			(layer "F.SilkS")
		)
		(fp_line
			(start -0.7874 -0.4064)
			(end 0.7874 -0.4064)
			(stroke
				(width 0.1524)
				(type default)
			)
			(layer "F.SilkS")
		)
		(fp_line
			(start 0.7874 0.4064)
			(end -0.7874 0.4064)
			(stroke
				(width 0.1524)
				(type default)
			)
			(layer "F.SilkS")
		)
		(fp_line
			(start -0.7874 0.4064)
			(end -0.7874 -0.4064)
			(stroke
				(width 0.1524)
				(type default)
			)
			(layer "F.SilkS")
		)
		(fp_line
			(start -0.12065 -0.305054)
			(end -0.12065 -0.2794)
			(stroke
				(width 0.1)
				(type default)
			)
			(layer "F.Fab")
		)
		(fp_line
			(start -0.67945 -0.305054)
			(end -0.12065 -0.305054)
			(stroke
				(width 0.1)
				(type default)
			)
			(layer "F.Fab")
		)
		(fp_line
			(start 0.67945 -0.3048)
			(end 0.67945 0.3048)
			(stroke
				(width 0.1)
				(type default)
			)
			(layer "F.Fab")
		)
		(fp_line
			(start 0.12065 -0.3048)
			(end 0.67945 -0.3048)
			(stroke
				(width 0.1)
				(type default)
			)
			(layer "F.Fab")
		)
		(fp_line
			(start 0.12065 -0.2794)
			(end 0.12065 -0.3048)
			(stroke
				(width 0.1)
				(type default)
			)
			(layer "F.Fab")
		)
		(fp_line
			(start -0.12065 -0.2794)
			(end 0.12065 -0.2794)
			(stroke
				(width 0.1)
				(type default)
			)
			(layer "F.Fab")
		)
		(fp_line
			(start 0.120396 0.2794)
			(end -0.12065 0.2794)
			(stroke
				(width 0.1)
				(type default)
			)
			(layer "F.Fab")
		)
		(fp_line
			(start -0.12065 0.2794)
			(end -0.12065 0.3048)
			(stroke
				(width 0.1)
				(type default)
			)
			(layer "F.Fab")
		)
		(fp_line
			(start 0.67945 0.3048)
			(end 0.120396 0.3048)
			(stroke
				(width 0.1)
				(type default)
			)
			(layer "F.Fab")
		)
		(fp_line
			(start 0.120396 0.3048)
			(end 0.120396 0.2794)
			(stroke
				(width 0.1)
				(type default)
			)
			(layer "F.Fab")
		)
		(fp_line
			(start -0.12065 0.3048)
			(end -0.67945 0.3048)
			(stroke
				(width 0.1)
				(type default)
			)
			(layer "F.Fab")
		)
		(fp_line
			(start -0.67945 0.3048)
			(end -0.67945 -0.305054)
			(stroke
				(width 0.1)
				(type default)
			)
			(layer "F.Fab")
		)
		(pad "1" smd circle
			(at -0.40005 0 90)
			(size 0 0)
			(layers "F.Cu" "F.Mask" "F.Paste")
			(net "PWRGD_P1V8_AUX_R3")
		)
		(pad "2" smd circle
			(at 0.40005 0 90)
			(size 0 0)
			(layers "F.Cu" "F.Mask" "F.Paste")
			(net "EN_P3V3_RGM_R")
		)
	)
)
